(kicad_pcb
	(version 20260206)
	(generator "pcbnew")
	(generator_version "10.0")
	(general
		(thickness 1.6)
		(legacy_teardrops no)
	)
	(paper "A4")
	(title_block
		(title "04192023_DAF0TMB3IC0_F0TG_MB_C_brd_V02_OCP.brd")
		(comment 1 "Grand Teton / footprints 6784-6790 of 8354")
	)
	(layers
		(0 "F.Cu" signal "TOP")
		(4 "In1.Cu" signal "GND")
		(6 "In2.Cu" signal "IN1")
		(8 "In3.Cu" signal "GND1")
		(10 "In4.Cu" signal "IN2")
		(12 "In5.Cu" signal "GND2")
		(14 "In6.Cu" signal "IN3")
		(16 "In7.Cu" signal "GND3")
		(18 "In8.Cu" signal "VCC")
		(20 "In9.Cu" signal "VCC1")
		(22 "In10.Cu" signal "GND4")
		(24 "In11.Cu" signal "IN4")
		(26 "In12.Cu" signal "GND5")
		(28 "In13.Cu" signal "IN5")
		(30 "In14.Cu" signal "GND6")
		(32 "In15.Cu" signal "IN6")
		(34 "In16.Cu" signal "GND7")
		(2 "B.Cu" signal "BOTTOM")
		(9 "F.Adhes" user "F.Adhesive")
		(11 "B.Adhes" user "B.Adhesive")
		(13 "F.Paste" user "Package Geometry/Pastemask Top")
		(15 "B.Paste" user "Package Geometry/Pastemask Bottom")
		(5 "F.SilkS" user "Ref Des/Silkscreen Top")
		(7 "B.SilkS" user "Ref Des/Silkscreen Bottom")
		(1 "F.Mask" user "Board Geometry/Soldermask Top")
		(3 "B.Mask" user "Board Geometry/Soldermask Bottom")
		(17 "Dwgs.User" user "User.Drawings")
		(19 "Cmts.User" user "User.Comments")
		(21 "Eco1.User" user "User.Eco1")
		(23 "Eco2.User" user "User.Eco2")
		(25 "Edge.Cuts" user "Board Geometry/Outline")
		(27 "Margin" user)
		(31 "F.CrtYd" user "Package Geometry/Place Bound Top")
		(29 "B.CrtYd" user "Package Geometry/Place Bound Bottom")
		(35 "F.Fab" user "Ref Des/Assembly Top")
		(33 "B.Fab" user "Ref Des/Assembly Bottom")
	)
	(footprint ""
		(layer "B.Cu")
		(at 413.975804 -361.427014 -90)
		(property "Reference" "PR127"
			(at 0 0 90)
			(layer "B.SilkS")
			(hide yes)
			(effects
				(font
					(size 1.27 1.27)
				)
				(justify mirror)
			)
		)
		(property "Value" ""
			(at 0 0 90)
			(layer "B.Fab")
			(effects
				(font
					(size 1.27 1.27)
				)
				(justify mirror)
			)
		)
		(duplicate_pad_numbers_are_jumpers no)
		(fp_line
			(start -0.7874 0.4064)
			(end 0.7874 0.4064)
			(stroke
				(width 0.1524)
				(type default)
			)
			(layer "B.SilkS")
		)
		(fp_line
			(start 0.7874 0.4064)
			(end 0.7874 -0.4064)
			(stroke
				(width 0.1524)
				(type default)
			)
			(layer "B.SilkS")
		)
		(fp_line
			(start -0.7874 -0.4064)
			(end -0.7874 0.4064)
			(stroke
				(width 0.1524)
				(type default)
			)
			(layer "B.SilkS")
		)
		(fp_line
			(start 0.7874 -0.4064)
			(end -0.7874 -0.4064)
			(stroke
				(width 0.1524)
				(type default)
			)
			(layer "B.SilkS")
		)
		(fp_line
			(start -0.67945 0.3048)
			(end -0.120396 0.3048)
			(stroke
				(width 0.1)
				(type default)
			)
			(layer "B.Fab")
		)
		(fp_line
			(start -0.120396 0.3048)
			(end -0.120396 0.2794)
			(stroke
				(width 0.1)
				(type default)
			)
			(layer "B.Fab")
		)
		(fp_line
			(start 0.12065 0.3048)
			(end 0.67945 0.3048)
			(stroke
				(width 0.1)
				(type default)
			)
			(layer "B.Fab")
		)
		(fp_line
			(start 0.67945 0.3048)
			(end 0.67945 -0.305054)
			(stroke
				(width 0.1)
				(type default)
			)
			(layer "B.Fab")
		)
		(fp_line
			(start -0.120396 0.2794)
			(end 0.12065 0.2794)
			(stroke
				(width 0.1)
				(type default)
			)
			(layer "B.Fab")
		)
		(fp_line
			(start 0.12065 0.2794)
			(end 0.12065 0.3048)
			(stroke
				(width 0.1)
				(type default)
			)
			(layer "B.Fab")
		)
		(fp_line
			(start -0.12065 -0.2794)
			(end -0.12065 -0.3048)
			(stroke
				(width 0.1)
				(type default)
			)
			(layer "B.Fab")
		)
		(fp_line
			(start 0.12065 -0.2794)
			(end -0.12065 -0.2794)
			(stroke
				(width 0.1)
				(type default)
			)
			(layer "B.Fab")
		)
		(fp_line
			(start -0.67945 -0.3048)
			(end -0.67945 0.3048)
			(stroke
				(width 0.1)
				(type default)
			)
			(layer "B.Fab")
		)
		(fp_line
			(start -0.12065 -0.3048)
			(end -0.67945 -0.3048)
			(stroke
				(width 0.1)
				(type default)
			)
			(layer "B.Fab")
		)
		(fp_line
			(start 0.12065 -0.305054)
			(end 0.12065 -0.2794)
			(stroke
				(width 0.1)
				(type default)
			)
			(layer "B.Fab")
		)
		(fp_line
			(start 0.67945 -0.305054)
			(end 0.12065 -0.305054)
			(stroke
				(width 0.1)
				(type default)
			)
			(layer "B.Fab")
		)
		(pad "1" smd circle
			(at 0.40005 0 90)
			(size 0 0)
			(layers "B.Cu" "B.Mask" "B.Paste")
			(net "PVDD11_S3_P0_RESET_N_R")
		)
		(pad "2" smd circle
			(at -0.40005 0 90)
			(size 0 0)
			(layers "B.Cu" "B.Mask" "B.Paste")
			(net "GND")
		)
	)
	(footprint ""
		(layer "B.Cu")
		(at 14.840458 -418.817298)
		(property "Reference" "C6010"
			(at 0 0 0)
			(layer "B.SilkS")
			(hide yes)
			(effects
				(font
					(size 1.27 1.27)
				)
				(justify mirror)
			)
		)
		(property "Value" ""
			(at 0 0 0)
			(layer "B.Fab")
			(effects
				(font
					(size 1.27 1.27)
				)
				(justify mirror)
			)
		)
		(duplicate_pad_numbers_are_jumpers no)
		(fp_line
			(start -1.524 -0.762)
			(end -1.524 0.762)
			(stroke
				(width 0.1524)
				(type default)
			)
			(layer "B.SilkS")
		)
		(fp_line
			(start -1.524 0.762)
			(end 1.524 0.762)
			(stroke
				(width 0.1524)
				(type default)
			)
			(layer "B.SilkS")
		)
		(fp_line
			(start 1.524 -0.762)
			(end -1.524 -0.762)
			(stroke
				(width 0.1524)
				(type default)
			)
			(layer "B.SilkS")
		)
		(fp_line
			(start 1.524 0.762)
			(end 1.524 -0.762)
			(stroke
				(width 0.1524)
				(type default)
			)
			(layer "B.SilkS")
		)
		(fp_line
			(start -1.1049 -0.724916)
			(end 1.1049 -0.724916)
			(stroke
				(width 0.1)
				(type default)
			)
			(layer "B.Fab")
		)
		(fp_line
			(start -1.1049 0.724916)
			(end -1.1049 -0.724916)
			(stroke
				(width 0.1)
				(type default)
			)
			(layer "B.Fab")
		)
		(fp_line
			(start 1.1049 -0.724916)
			(end 1.1049 0.724916)
			(stroke
				(width 0.1)
				(type default)
			)
			(layer "B.Fab")
		)
		(fp_line
			(start 1.1049 0.724916)
			(end -1.1049 0.724916)
			(stroke
				(width 0.1)
				(type default)
			)
			(layer "B.Fab")
		)
		(pad "1" smd rect
			(at 0.889 0)
			(size 1.016 1.27)
			(layers "B.Cu" "B.Mask" "B.Paste")
			(net "P3V3_AUX")
		)
		(pad "2" smd rect
			(at -0.889 0)
			(size 1.016 1.27)
			(layers "B.Cu" "B.Mask" "B.Paste")
			(net "GND")
		)
	)
	(footprint ""
		(layer "B.Cu")
		(at 94.488 -301.716948)
		(property "Reference" "R5032"
			(at 0 0 0)
			(layer "B.SilkS")
			(hide yes)
			(effects
				(font
					(size 1.27 1.27)
				)
				(justify mirror)
			)
		)
		(property "Value" ""
			(at 0 0 0)
			(layer "B.Fab")
			(effects
				(font
					(size 1.27 1.27)
				)
				(justify mirror)
			)
		)
		(duplicate_pad_numbers_are_jumpers no)
		(fp_line
			(start -0.7874 -0.4064)
			(end -0.7874 0.4064)
			(stroke
				(width 0.1524)
				(type default)
			)
			(layer "B.SilkS")
		)
		(fp_line
			(start -0.7874 0.4064)
			(end 0.7874 0.4064)
			(stroke
				(width 0.1524)
				(type default)
			)
			(layer "B.SilkS")
		)
		(fp_line
			(start 0.7874 -0.4064)
			(end -0.7874 -0.4064)
			(stroke
				(width 0.1524)
				(type default)
			)
			(layer "B.SilkS")
		)
		(fp_line
			(start 0.7874 0.4064)
			(end 0.7874 -0.4064)
			(stroke
				(width 0.1524)
				(type default)
			)
			(layer "B.SilkS")
		)
		(fp_line
			(start -0.67945 -0.3048)
			(end -0.67945 0.3048)
			(stroke
				(width 0.1)
				(type default)
			)
			(layer "B.Fab")
		)
		(fp_line
			(start -0.67945 0.3048)
			(end -0.120396 0.3048)
			(stroke
				(width 0.1)
				(type default)
			)
			(layer "B.Fab")
		)
		(fp_line
			(start -0.12065 -0.3048)
			(end -0.67945 -0.3048)
			(stroke
				(width 0.1)
				(type default)
			)
			(layer "B.Fab")
		)
		(fp_line
			(start -0.12065 -0.2794)
			(end -0.12065 -0.3048)
			(stroke
				(width 0.1)
				(type default)
			)
			(layer "B.Fab")
		)
		(fp_line
			(start -0.120396 0.2794)
			(end 0.12065 0.2794)
			(stroke
				(width 0.1)
				(type default)
			)
			(layer "B.Fab")
		)
		(fp_line
			(start -0.120396 0.3048)
			(end -0.120396 0.2794)
			(stroke
				(width 0.1)
				(type default)
			)
			(layer "B.Fab")
		)
		(fp_line
			(start 0.12065 -0.305054)
			(end 0.12065 -0.2794)
			(stroke
				(width 0.1)
				(type default)
			)
			(layer "B.Fab")
		)
		(fp_line
			(start 0.12065 -0.2794)
			(end -0.12065 -0.2794)
			(stroke
				(width 0.1)
				(type default)
			)
			(layer "B.Fab")
		)
		(fp_line
			(start 0.12065 0.2794)
			(end 0.12065 0.3048)
			(stroke
				(width 0.1)
				(type default)
			)
			(layer "B.Fab")
		)
		(fp_line
			(start 0.12065 0.3048)
			(end 0.67945 0.3048)
			(stroke
				(width 0.1)
				(type default)
			)
			(layer "B.Fab")
		)
		(fp_line
			(start 0.67945 -0.305054)
			(end 0.12065 -0.305054)
			(stroke
				(width 0.1)
				(type default)
			)
			(layer "B.Fab")
		)
		(fp_line
			(start 0.67945 0.3048)
			(end 0.67945 -0.305054)
			(stroke
				(width 0.1)
				(type default)
			)
			(layer "B.Fab")
		)
		(pad "1" smd circle
			(at 0.40005 0 180)
			(size 0 0)
			(layers "B.Cu" "B.Mask" "B.Paste")
			(net "GND")
		)
		(pad "2" smd circle
			(at -0.40005 0 180)
			(size 0 0)
			(layers "B.Cu" "B.Mask" "B.Paste")
			(net "IRQ_CPU_BMC_NMI_N")
		)
	)
	(footprint ""
		(layer "B.Cu")
		(at 246.01932 -53.923946 -90)
		(property "Reference" "PC2280"
			(at 0 0 90)
			(layer "B.SilkS")
			(hide yes)
			(effects
				(font
					(size 1.27 1.27)
				)
				(justify mirror)
			)
		)
		(property "Value" ""
			(at 0 0 90)
			(layer "B.Fab")
			(effects
				(font
					(size 1.27 1.27)
				)
				(justify mirror)
			)
		)
		(duplicate_pad_numbers_are_jumpers no)
		(fp_line
			(start -1.524 0.762)
			(end 1.524 0.762)
			(stroke
				(width 0.1524)
				(type default)
			)
			(layer "B.SilkS")
		)
		(fp_line
			(start 1.524 0.762)
			(end 1.524 -0.762)
			(stroke
				(width 0.1524)
				(type default)
			)
			(layer "B.SilkS")
		)
		(fp_line
			(start -1.524 -0.762)
			(end -1.524 0.762)
			(stroke
				(width 0.1524)
				(type default)
			)
			(layer "B.SilkS")
		)
		(fp_line
			(start 1.524 -0.762)
			(end -1.524 -0.762)
			(stroke
				(width 0.1524)
				(type default)
			)
			(layer "B.SilkS")
		)
		(fp_line
			(start -1.1049 0.724916)
			(end -1.1049 -0.724916)
			(stroke
				(width 0.1)
				(type default)
			)
			(layer "B.Fab")
		)
		(fp_line
			(start 1.1049 0.724916)
			(end -1.1049 0.724916)
			(stroke
				(width 0.1)
				(type default)
			)
			(layer "B.Fab")
		)
		(fp_line
			(start -1.1049 -0.724916)
			(end 1.1049 -0.724916)
			(stroke
				(width 0.1)
				(type default)
			)
			(layer "B.Fab")
		)
		(fp_line
			(start 1.1049 -0.724916)
			(end 1.1049 0.724916)
			(stroke
				(width 0.1)
				(type default)
			)
			(layer "B.Fab")
		)
		(pad "1" smd rect
			(at 0.889 0 270)
			(size 1.016 1.27)
			(layers "B.Cu" "B.Mask" "B.Paste")
			(net "P12V_E1S_0")
		)
		(pad "2" smd rect
			(at -0.889 0 270)
			(size 1.016 1.27)
			(layers "B.Cu" "B.Mask" "B.Paste")
			(net "GND")
		)
	)
	(footprint ""
		(layer "B.Cu")
		(at 346.373958 -261.870952)
		(property "Reference" "C2605"
			(at 0 0 0)
			(layer "B.SilkS")
			(hide yes)
			(effects
				(font
					(size 1.27 1.27)
				)
				(justify mirror)
			)
		)
		(property "Value" ""
			(at 0 0 0)
			(layer "B.Fab")
			(effects
				(font
					(size 1.27 1.27)
				)
				(justify mirror)
			)
		)
		(duplicate_pad_numbers_are_jumpers no)
		(fp_line
			(start -0.7874 -0.4064)
			(end -0.7874 0.4064)
			(stroke
				(width 0.1524)
				(type default)
			)
			(layer "B.SilkS")
		)
		(fp_line
			(start -0.7874 0.4064)
			(end 0.7874 0.4064)
			(stroke
				(width 0.1524)
				(type default)
			)
			(layer "B.SilkS")
		)
		(fp_line
			(start 0.7874 -0.4064)
			(end -0.7874 -0.4064)
			(stroke
				(width 0.1524)
				(type default)
			)
			(layer "B.SilkS")
		)
		(fp_line
			(start 0.7874 0.4064)
			(end 0.7874 -0.4064)
			(stroke
				(width 0.1524)
				(type default)
			)
			(layer "B.SilkS")
		)
		(fp_line
			(start -0.67945 -0.3048)
			(end -0.67945 0.3048)
			(stroke
				(width 0.1)
				(type default)
			)
			(layer "B.Fab")
		)
		(fp_line
			(start -0.67945 0.3048)
			(end -0.120396 0.3048)
			(stroke
				(width 0.1)
				(type default)
			)
			(layer "B.Fab")
		)
		(fp_line
			(start -0.12065 -0.3048)
			(end -0.67945 -0.3048)
			(stroke
				(width 0.1)
				(type default)
			)
			(layer "B.Fab")
		)
		(fp_line
			(start -0.12065 -0.2794)
			(end -0.12065 -0.3048)
			(stroke
				(width 0.1)
				(type default)
			)
			(layer "B.Fab")
		)
		(fp_line
			(start -0.120396 0.2794)
			(end 0.12065 0.2794)
			(stroke
				(width 0.1)
				(type default)
			)
			(layer "B.Fab")
		)
		(fp_line
			(start -0.120396 0.3048)
			(end -0.120396 0.2794)
			(stroke
				(width 0.1)
				(type default)
			)
			(layer "B.Fab")
		)
		(fp_line
			(start 0.12065 -0.305054)
			(end 0.12065 -0.2794)
			(stroke
				(width 0.1)
				(type default)
			)
			(layer "B.Fab")
		)
		(fp_line
			(start 0.12065 -0.2794)
			(end -0.12065 -0.2794)
			(stroke
				(width 0.1)
				(type default)
			)
			(layer "B.Fab")
		)
		(fp_line
			(start 0.12065 0.2794)
			(end 0.12065 0.3048)
			(stroke
				(width 0.1)
				(type default)
			)
			(layer "B.Fab")
		)
		(fp_line
			(start 0.12065 0.3048)
			(end 0.67945 0.3048)
			(stroke
				(width 0.1)
				(type default)
			)
			(layer "B.Fab")
		)
		(fp_line
			(start 0.67945 -0.305054)
			(end 0.12065 -0.305054)
			(stroke
				(width 0.1)
				(type default)
			)
			(layer "B.Fab")
		)
		(fp_line
			(start 0.67945 0.3048)
			(end 0.67945 -0.305054)
			(stroke
				(width 0.1)
				(type default)
			)
			(layer "B.Fab")
		)
		(pad "1" smd circle
			(at 0.40005 0 180)
			(size 0 0)
			(layers "B.Cu" "B.Mask" "B.Paste")
			(net "PVDDIO_P0")
		)
		(pad "2" smd circle
			(at -0.40005 0 180)
			(size 0 0)
			(layers "B.Cu" "B.Mask" "B.Paste")
			(net "GND")
		)
	)
	(footprint ""
		(layer "B.Cu")
		(at 396.052802 -314.366148)
		(property "Reference" "C213"
			(at 0 0 0)
			(layer "B.SilkS")
			(hide yes)
			(effects
				(font
					(size 1.27 1.27)
				)
				(justify mirror)
			)
		)
		(property "Value" ""
			(at 0 0 0)
			(layer "B.Fab")
			(effects
				(font
					(size 1.27 1.27)
				)
				(justify mirror)
			)
		)
		(duplicate_pad_numbers_are_jumpers no)
		(fp_line
			(start -0.7874 -0.4064)
			(end -0.7874 0.4064)
			(stroke
				(width 0.1524)
				(type default)
			)
			(layer "B.SilkS")
		)
		(fp_line
			(start -0.7874 0.4064)
			(end 0.7874 0.4064)
			(stroke
				(width 0.1524)
				(type default)
			)
			(layer "B.SilkS")
		)
		(fp_line
			(start 0.7874 -0.4064)
			(end -0.7874 -0.4064)
			(stroke
				(width 0.1524)
				(type default)
			)
			(layer "B.SilkS")
		)
		(fp_line
			(start 0.7874 0.4064)
			(end 0.7874 -0.4064)
			(stroke
				(width 0.1524)
				(type default)
			)
			(layer "B.SilkS")
		)
		(fp_line
			(start -0.67945 -0.3048)
			(end -0.67945 0.3048)
			(stroke
				(width 0.1)
				(type default)
			)
			(layer "B.Fab")
		)
		(fp_line
			(start -0.67945 0.3048)
			(end -0.120396 0.3048)
			(stroke
				(width 0.1)
				(type default)
			)
			(layer "B.Fab")
		)
		(fp_line
			(start -0.12065 -0.3048)
			(end -0.67945 -0.3048)
			(stroke
				(width 0.1)
				(type default)
			)
			(layer "B.Fab")
		)
		(fp_line
			(start -0.12065 -0.2794)
			(end -0.12065 -0.3048)
			(stroke
				(width 0.1)
				(type default)
			)
			(layer "B.Fab")
		)
		(fp_line
			(start -0.120396 0.2794)
			(end 0.12065 0.2794)
			(stroke
				(width 0.1)
				(type default)
			)
			(layer "B.Fab")
		)
		(fp_line
			(start -0.120396 0.3048)
			(end -0.120396 0.2794)
			(stroke
				(width 0.1)
				(type default)
			)
			(layer "B.Fab")
		)
		(fp_line
			(start 0.12065 -0.305054)
			(end 0.12065 -0.2794)
			(stroke
				(width 0.1)
				(type default)
			)
			(layer "B.Fab")
		)
		(fp_line
			(start 0.12065 -0.2794)
			(end -0.12065 -0.2794)
			(stroke
				(width 0.1)
				(type default)
			)
			(layer "B.Fab")
		)
		(fp_line
			(start 0.12065 0.2794)
			(end 0.12065 0.3048)
			(stroke
				(width 0.1)
				(type default)
			)
			(layer "B.Fab")
		)
		(fp_line
			(start 0.12065 0.3048)
			(end 0.67945 0.3048)
			(stroke
				(width 0.1)
				(type default)
			)
			(layer "B.Fab")
		)
		(fp_line
			(start 0.67945 -0.305054)
			(end 0.12065 -0.305054)
			(stroke
				(width 0.1)
				(type default)
			)
			(layer "B.Fab")
		)
		(fp_line
			(start 0.67945 0.3048)
			(end 0.67945 -0.305054)
			(stroke
				(width 0.1)
				(type default)
			)
			(layer "B.Fab")
		)
		(pad "1" smd circle
			(at 0.40005 0 180)
			(size 0 0)
			(layers "B.Cu" "B.Mask" "B.Paste")
			(net "XTAL_CPU0_X48M_X1")
		)
		(pad "2" smd circle
			(at -0.40005 0 180)
			(size 0 0)
			(layers "B.Cu" "B.Mask" "B.Paste")
			(net "GND")
		)
	)
	(footprint ""
		(layer "B.Cu")
		(at 239.903 -216.027)
		(property "Reference" "R365"
			(at 0 0 0)
			(layer "B.SilkS")
			(hide yes)
			(effects
				(font
					(size 1.27 1.27)
				)
				(justify mirror)
			)
		)
		(property "Value" ""
			(at 0 0 0)
			(layer "B.Fab")
			(effects
				(font
					(size 1.27 1.27)
				)
				(justify mirror)
			)
		)
		(duplicate_pad_numbers_are_jumpers no)
		(fp_line
			(start -0.7874 -0.4064)
			(end -0.7874 0.4064)
			(stroke
				(width 0.1524)
				(type default)
			)
			(layer "B.SilkS")
		)
		(fp_line
			(start -0.7874 0.4064)
			(end 0.7874 0.4064)
			(stroke
				(width 0.1524)
				(type default)
			)
			(layer "B.SilkS")
		)
		(fp_line
			(start 0.7874 -0.4064)
			(end -0.7874 -0.4064)
			(stroke
				(width 0.1524)
				(type default)
			)
			(layer "B.SilkS")
		)
		(fp_line
			(start 0.7874 0.4064)
			(end 0.7874 -0.4064)
			(stroke
				(width 0.1524)
				(type default)
			)
			(layer "B.SilkS")
		)
		(fp_line
			(start -0.67945 -0.3048)
			(end -0.67945 0.3048)
			(stroke
				(width 0.1)
				(type default)
			)
			(layer "B.Fab")
		)
		(fp_line
			(start -0.67945 0.3048)
			(end -0.120396 0.3048)
			(stroke
				(width 0.1)
				(type default)
			)
			(layer "B.Fab")
		)
		(fp_line
			(start -0.12065 -0.3048)
			(end -0.67945 -0.3048)
			(stroke
				(width 0.1)
				(type default)
			)
			(layer "B.Fab")
		)
		(fp_line
			(start -0.12065 -0.2794)
			(end -0.12065 -0.3048)
			(stroke
				(width 0.1)
				(type default)
			)
			(layer "B.Fab")
		)
		(fp_line
			(start -0.120396 0.2794)
			(end 0.12065 0.2794)
			(stroke
				(width 0.1)
				(type default)
			)
			(layer "B.Fab")
		)
		(fp_line
			(start -0.120396 0.3048)
			(end -0.120396 0.2794)
			(stroke
				(width 0.1)
				(type default)
			)
			(layer "B.Fab")
		)
		(fp_line
			(start 0.12065 -0.305054)
			(end 0.12065 -0.2794)
			(stroke
				(width 0.1)
				(type default)
			)
			(layer "B.Fab")
		)
		(fp_line
			(start 0.12065 -0.2794)
			(end -0.12065 -0.2794)
			(stroke
				(width 0.1)
				(type default)
			)
			(layer "B.Fab")
		)
		(fp_line
			(start 0.12065 0.2794)
			(end 0.12065 0.3048)
			(stroke
				(width 0.1)
				(type default)
			)
			(layer "B.Fab")
		)
		(fp_line
			(start 0.12065 0.3048)
			(end 0.67945 0.3048)
			(stroke
				(width 0.1)
				(type default)
			)
			(layer "B.Fab")
		)
		(fp_line
			(start 0.67945 -0.305054)
			(end 0.12065 -0.305054)
			(stroke
				(width 0.1)
				(type default)
			)
			(layer "B.Fab")
		)
		(fp_line
			(start 0.67945 0.3048)
			(end 0.67945 -0.305054)
			(stroke
				(width 0.1)
				(type default)
			)
			(layer "B.Fab")
		)
		(pad "1" smd circle
			(at 0.40005 0 180)
			(size 0 0)
			(layers "B.Cu" "B.Mask" "B.Paste")
			(net "P3V3")
		)
		(pad "2" smd circle
			(at -0.40005 0 180)
			(size 0 0)
			(layers "B.Cu" "B.Mask" "B.Paste")
			(net "SMB_CPU0_CPU1_APML_BUF1_SDA_R2")
		)
	)
)
